# T6G (Grand Teton) — schematic netlist excerpt (pin names and nets, part order shuffled) for the footprints in the layout excerpt that follows; sources: Cadence DE-HDL packaged netlist, KiCad conversion of 04192023_DAF0TMB3IC0_F0TG_MB_C_brd_V02_OCP.brd

R1118  Q_RES  4.7K 5% CHIP  pkg 0201LF  page 309 : A = TEST1_RT_CPU0_P3 ; B = GND
C281  Q_CAP  0.1UF 10V 10% X7S  pkg C0201  page 323 : A = P0V9_CPU1_RT0_2A ; B = GND
R93  Q_RES  1K 1% EMPTY  pkg 0402LF  page 90 : A = P3V3 ; B = PWRGD_CHE_CPU0_DIMM

(kicad_pcb
	(version 20260206)
	(generator "pcbnew")
	(generator_version "10.0")
	(general
		(thickness 1.6)
		(legacy_teardrops no)
	)
	(paper "A4")
	(title_block
		(title "04192023_DAF0TMB3IC0_F0TG_MB_C_brd_V02_OCP.brd")
		(comment 1 "Grand Teton / footprints 5732-5734 of 8354")
	)
	(layers
		(0 "F.Cu" signal "TOP")
		(4 "In1.Cu" signal "GND")
		(6 "In2.Cu" signal "IN1")
		(8 "In3.Cu" signal "GND1")
		(10 "In4.Cu" signal "IN2")
		(12 "In5.Cu" signal "GND2")
		(14 "In6.Cu" signal "IN3")
		(16 "In7.Cu" signal "GND3")
		(18 "In8.Cu" signal "VCC")
		(20 "In9.Cu" signal "VCC1")
		(22 "In10.Cu" signal "GND4")
		(24 "In11.Cu" signal "IN4")
		(26 "In12.Cu" signal "GND5")
		(28 "In13.Cu" signal "IN5")
		(30 "In14.Cu" signal "GND6")
		(32 "In15.Cu" signal "IN6")
		(34 "In16.Cu" signal "GND7")
		(2 "B.Cu" signal "BOTTOM")
		(9 "F.Adhes" user "F.Adhesive")
		(11 "B.Adhes" user "B.Adhesive")
		(13 "F.Paste" user "Package Geometry/Pastemask Top")
		(15 "B.Paste" user "Package Geometry/Pastemask Bottom")
		(5 "F.SilkS" user "Ref Des/Silkscreen Top")
		(7 "B.SilkS" user "Ref Des/Silkscreen Bottom")
		(1 "F.Mask" user "Board Geometry/Soldermask Top")
		(3 "B.Mask" user "Board Geometry/Soldermask Bottom")
		(17 "Dwgs.User" user "User.Drawings")
		(19 "Cmts.User" user "User.Comments")
		(21 "Eco1.User" user "User.Eco1")
		(23 "Eco2.User" user "User.Eco2")
		(25 "Edge.Cuts" user "Board Geometry/Outline")
		(27 "Margin" user)
		(31 "F.CrtYd" user "Package Geometry/Place Bound Top")
		(29 "B.CrtYd" user "Package Geometry/Place Bound Bottom")
		(35 "F.Fab" user "Ref Des/Assembly Top")
		(33 "B.Fab" user "Ref Des/Assembly Bottom")
	)
	(footprint ""
		(layer "B.Cu")
		(at 45.099986 -388.609078 90)
		(property "Reference" "C281"
			(at 0 0 90)
			(layer "B.SilkS")
			(hide yes)
			(effects
				(font
					(size 1.27 1.27)
				)
				(justify mirror)
			)
		)
		(property "Value" ""
			(at 0 0 90)
			(layer "B.Fab")
			(effects
				(font
					(size 1.27 1.27)
				)
				(justify mirror)
			)
		)
		(duplicate_pad_numbers_are_jumpers no)
		(fp_line
			(start 0.299974 -0.150114)
			(end -0.299974 -0.150114)
			(stroke
				(width 0.1)
				(type default)
			)
			(layer "B.Fab")
		)
		(fp_line
			(start -0.299974 -0.150114)
			(end -0.299974 0.150114)
			(stroke
				(width 0.1)
				(type default)
			)
			(layer "B.Fab")
		)
		(fp_line
			(start 0.299974 0.150114)
			(end 0.299974 -0.150114)
			(stroke
				(width 0.1)
				(type default)
			)
			(layer "B.Fab")
		)
		(fp_line
			(start -0.299974 0.150114)
			(end 0.299974 0.150114)
			(stroke
				(width 0.1)
				(type default)
			)
			(layer "B.Fab")
		)
		(pad "1" smd rect
			(at 0.2667 0 270)
			(size 0.3048 0.381)
			(layers "B.Cu" "B.Mask" "B.Paste")
			(net "P0V9_CPU1_RT0_2A")
		)
		(pad "2" smd rect
			(at -0.2667 0 270)
			(size 0.3048 0.381)
			(layers "B.Cu" "B.Mask" "B.Paste")
			(net "GND")
		)
	)
	(footprint ""
		(layer "B.Cu")
		(at 366.36579 -393.04468 180)
		(property "Reference" "R1118"
			(at 0 0 0)
			(layer "B.SilkS")
			(hide yes)
			(effects
				(font
					(size 1.27 1.27)
				)
				(justify mirror)
			)
		)
		(property "Value" ""
			(at 0 0 0)
			(layer "B.Fab")
			(effects
				(font
					(size 1.27 1.27)
				)
				(justify mirror)
			)
		)
		(duplicate_pad_numbers_are_jumpers no)
		(fp_line
			(start 0.32512 0.175006)
			(end 0.32512 -0.175006)
			(stroke
				(width 0.1)
				(type default)
			)
			(layer "B.Fab")
		)
		(fp_line
			(start 0.32512 -0.175006)
			(end -0.32512 -0.175006)
			(stroke
				(width 0.1)
				(type default)
			)
			(layer "B.Fab")
		)
		(fp_line
			(start -0.32512 0.175006)
			(end 0.32512 0.175006)
			(stroke
				(width 0.1)
				(type default)
			)
			(layer "B.Fab")
		)
		(fp_line
			(start -0.32512 -0.175006)
			(end -0.32512 0.175006)
			(stroke
				(width 0.1)
				(type default)
			)
			(layer "B.Fab")
		)
		(pad "1" smd rect
			(at 0.2667 0)
			(size 0.3048 0.381)
			(layers "B.Cu" "B.Mask" "B.Paste")
			(net "TEST1_RT_CPU0_P3")
		)
		(pad "2" smd rect
			(at -0.2667 0 180)
			(size 0.3048 0.381)
			(layers "B.Cu" "B.Mask" "B.Paste")
			(net "GND")
		)
	)
	(footprint ""
		(layer "B.Cu")
		(at 273.847814 -193.99631)
		(property "Reference" "R93"
			(at 0 0 0)
			(layer "B.SilkS")
			(hide yes)
			(effects
				(font
					(size 1.27 1.27)
				)
				(justify mirror)
			)
		)
		(property "Value" ""
			(at 0 0 0)
			(layer "B.Fab")
			(effects
				(font
					(size 1.27 1.27)
				)
				(justify mirror)
			)
		)
		(duplicate_pad_numbers_are_jumpers no)
		(fp_line
			(start -0.7874 -0.4064)
			(end -0.7874 0.4064)
			(stroke
				(width 0.1524)
				(type default)
			)
			(layer "B.SilkS")
		)
		(fp_line
			(start -0.7874 0.4064)
			(end 0.7874 0.4064)
			(stroke
				(width 0.1524)
				(type default)
			)
			(layer "B.SilkS")
		)
		(fp_line
			(start 0.7874 -0.4064)
			(end -0.7874 -0.4064)
			(stroke
				(width 0.1524)
				(type default)
			)
			(layer "B.SilkS")
		)
		(fp_line
			(start 0.7874 0.4064)
			(end 0.7874 -0.4064)
			(stroke
				(width 0.1524)
				(type default)
			)
			(layer "B.SilkS")
		)
		(fp_line
			(start -0.67945 -0.3048)
			(end -0.67945 0.3048)
			(stroke
				(width 0.1)
				(type default)
			)
			(layer "B.Fab")
		)
		(fp_line
			(start -0.67945 0.3048)
			(end -0.120396 0.3048)
			(stroke
				(width 0.1)
				(type default)
			)
			(layer "B.Fab")
		)
		(fp_line
			(start -0.12065 -0.3048)
			(end -0.67945 -0.3048)
			(stroke
				(width 0.1)
				(type default)
			)
			(layer "B.Fab")
		)
		(fp_line
			(start -0.12065 -0.2794)
			(end -0.12065 -0.3048)
			(stroke
				(width 0.1)
				(type default)
			)
			(layer "B.Fab")
		)
		(fp_line
			(start -0.120396 0.2794)
			(end 0.12065 0.2794)
			(stroke
				(width 0.1)
				(type default)
			)
			(layer "B.Fab")
		)
		(fp_line
			(start -0.120396 0.3048)
			(end -0.120396 0.2794)
			(stroke
				(width 0.1)
				(type default)
			)
			(layer "B.Fab")
		)
		(fp_line
			(start 0.12065 -0.305054)
			(end 0.12065 -0.2794)
			(stroke
				(width 0.1)
				(type default)
			)
			(layer "B.Fab")
		)
		(fp_line
			(start 0.12065 -0.2794)
			(end -0.12065 -0.2794)
			(stroke
				(width 0.1)
				(type default)
			)
			(layer "B.Fab")
		)
		(fp_line
			(start 0.12065 0.2794)
			(end 0.12065 0.3048)
			(stroke
				(width 0.1)
				(type default)
			)
			(layer "B.Fab")
		)
		(fp_line
			(start 0.12065 0.3048)
			(end 0.67945 0.3048)
			(stroke
				(width 0.1)
				(type default)
			)
			(layer "B.Fab")
		)
		(fp_line
			(start 0.67945 -0.305054)
			(end 0.12065 -0.305054)
			(stroke
				(width 0.1)
				(type default)
			)
			(layer "B.Fab")
		)
		(fp_line
			(start 0.67945 0.3048)
			(end 0.67945 -0.305054)
			(stroke
				(width 0.1)
				(type default)
			)
			(layer "B.Fab")
		)
		(pad "1" smd circle
			(at 0.40005 0 180)
			(size 0 0)
			(layers "B.Cu" "B.Mask" "B.Paste")
			(net "P3V3")
		)
		(pad "2" smd circle
			(at -0.40005 0 180)
			(size 0 0)
			(layers "B.Cu" "B.Mask" "B.Paste")
			(net "PWRGD_CHE_CPU0_DIMM")
		)
	)
)
